FILE_TYPE = MACRO_DRAWING;
SET COLOR_WIRE YELLOW;
SET COLOR_PROP ORANGE;
SET COLOR_DOT WHITE;
SET COLOR_ARC YELLOW;
SET COLOR_BODY GREEN;
SET COLOR_NOTE PURPLE;
SET PROP_DISPLAY VALUE;
SET PAGE_NUMBER P210;
FORCEADD OFFPAGE..5
(-3600 3850);
FORCEPROP 2 LAST $XR0 216 
J 0
(-3855 3850);
DISPLAY 0.638298 (-3855 3850);
PAINT MONO (-3855 3850);
FORCEPROP 2 LAST CDS_LIB standard
J 0
(-3600 3850);
PAINT MONO (-3600 3850);
DISPLAY INVISIBLE (-3600 3850);
FORCEPROP 1 LAST OFFPAGE TRUE
J 0
(-3275 3725);
DISPLAY 0.872340 (-3275 3725);
PAINT GREEN (-3275 3725);
DISPLAY INVISIBLE (-3275 3725);
FORCEPROP 1 LAST COMMENT_BODY TRUE
J 0
(-3500 3775);
DISPLAY 0.872340 (-3500 3775);
PAINT PEACH (-3500 3775);
DISPLAY INVISIBLE (-3500 3775);
FORCEPROP 2 LAST PATH I15
J 0
(-3550 3925);
DISPLAY 1.021277 (-3550 3925);
DISPLAY INVISIBLE (-3550 3925);
FORCEADD Q_RES..1
(-2125 3850);
FORCEPROP 1 LAST PART_NUMBER CS03322FB03
J 0
(-2250 3900);
DISPLAY 0.404255 (-2250 3900);
DISPLAY INVISIBLE (-2250 3900);
FORCEPROP 1 LAST TOLERANCE 1%
J 0
(-1950 3850);
DISPLAY 0.510638 (-1950 3850);
FORCEPROP 1 LAST PACK_TYPE 0402LF
J 0
(-1875 3850);
DISPLAY 0.510638 (-1875 3850);
FORCEPROP 1 LAST VALUE 33.2
J 2
(-1975 3850);
DISPLAY 0.510638 (-1975 3850);
FORCEPROP 1 LAST MATERIAL CHIP
J 0
(-2250 3925);
DISPLAY 0.404255 (-2250 3925);
FORCEPROP 1 LAST WATTAGE 1/16W
J 2
(-2025 3925);
DISPLAY 0.404255 (-2025 3925);
FORCEPROP 1 LAST $LOCATION R803
J 0
(-2375 3850);
DISPLAY 0.787234 (-2375 3850);
FORCEPROP 1 LASTPIN (-2225 3850) $PN 1
J 0
(-2213 3862);
DISPLAY 0.787234 (-2213 3862);
FORCEPROP 1 LASTPIN (-2025 3850) $PN 2
J 0
(-2063 3862);
DISPLAY 0.787234 (-2063 3862);
FORCEPROP 2 LAST CDS_LIB pure_quanta
J 0
(-2125 3850);
PAINT MONO (-2125 3850);
DISPLAY INVISIBLE (-2125 3850);
FORCEPROP 1 LAST PATH I19
J 0
(-2175 4000);
DISPLAY 0.978723 (-2175 4000);
PAINT WHITE (-2175 4000);
DISPLAY INVISIBLE (-2175 4000);
FORCEPROP 1 LAST $LOCATION R803
J 0
(-2175 4050);
DISPLAY 1.021277 (-2175 4050);
DISPLAY INVISIBLE (-2175 4050);
FORCEPROP 2 LAST CDS_LOCATION R803
J 0
(-2175 4050);
DISPLAY 1.021277 (-2175 4050);
DISPLAY INVISIBLE (-2175 4050);
FORCEPROP 2 LAST $SEC 1
J 0
(-2175 4050);
DISPLAY 0.680851 (-2175 4050);
PAINT MONO (-2175 4050);
DISPLAY INVISIBLE (-2175 4050);
FORCEPROP 2 LAST CDS_SEC 1
J 0
(-2175 4050);
DISPLAY 1.021277 (-2175 4050);
DISPLAY INVISIBLE (-2175 4050);
FORCEADD Q_RES..1
(-2125 3525);
FORCEPROP 1 LAST PART_NUMBER CS03322FB03
J 0
(-2250 3575);
DISPLAY 0.404255 (-2250 3575);
DISPLAY INVISIBLE (-2250 3575);
FORCEPROP 1 LAST TOLERANCE 1%
J 0
(-1950 3525);
DISPLAY 0.510638 (-1950 3525);
FORCEPROP 1 LAST VALUE 33.2
J 2
(-1975 3525);
DISPLAY 0.510638 (-1975 3525);
FORCEPROP 1 LAST PACK_TYPE 0402LF
J 0
(-1875 3525);
DISPLAY 0.510638 (-1875 3525);
FORCEPROP 1 LAST WATTAGE 1/16W
J 2
(-2025 3600);
DISPLAY 0.404255 (-2025 3600);
FORCEPROP 1 LAST MATERIAL CHIP
J 0
(-2250 3600);
DISPLAY 0.404255 (-2250 3600);
FORCEPROP 1 LAST $LOCATION R804
J 0
(-2375 3525);
DISPLAY 0.787234 (-2375 3525);
FORCEPROP 1 LASTPIN (-2225 3525) $PN 1
J 0
(-2213 3537);
DISPLAY 0.787234 (-2213 3537);
FORCEPROP 1 LASTPIN (-2025 3525) $PN 2
J 0
(-2063 3537);
DISPLAY 0.787234 (-2063 3537);
FORCEPROP 2 LAST CDS_LIB pure_quanta
J 0
(-2125 3525);
PAINT MONO (-2125 3525);
DISPLAY INVISIBLE (-2125 3525);
FORCEPROP 1 LAST PATH I20
J 0
(-2175 3675);
DISPLAY 0.978723 (-2175 3675);
PAINT WHITE (-2175 3675);
DISPLAY INVISIBLE (-2175 3675);
FORCEPROP 1 LAST $LOCATION R804
J 0
(-2175 3725);
DISPLAY 1.021277 (-2175 3725);
DISPLAY INVISIBLE (-2175 3725);
FORCEPROP 2 LAST CDS_LOCATION R804
J 0
(-2175 3725);
DISPLAY 1.021277 (-2175 3725);
DISPLAY INVISIBLE (-2175 3725);
FORCEPROP 2 LAST $SEC 1
J 0
(-2175 3725);
DISPLAY 0.680851 (-2175 3725);
PAINT MONO (-2175 3725);
DISPLAY INVISIBLE (-2175 3725);
FORCEPROP 2 LAST CDS_SEC 1
J 0
(-2175 3725);
DISPLAY 1.021277 (-2175 3725);
DISPLAY INVISIBLE (-2175 3725);
FORCEADD OFFPAGE..2
(325 3525);
FORCEPROP 2 LAST $XR1 239 
J 0
(634 3525);
DISPLAY 0.638298 (634 3525);
PAINT MONO (634 3525);
FORCEPROP 2 LAST $XR0 221 
J 0
(514 3525);
DISPLAY 0.638298 (514 3525);
PAINT MONO (514 3525);
FORCEPROP 2 LAST CDS_LIB standard
J 0
(325 3525);
PAINT MONO (325 3525);
DISPLAY INVISIBLE (325 3525);
FORCEPROP 1 LAST OFFPAGE TRUE
J 0
(650 3400);
DISPLAY 0.872340 (650 3400);
PAINT GREEN (650 3400);
DISPLAY INVISIBLE (650 3400);
FORCEPROP 1 LAST COMMENT_BODY TRUE
J 0
(280 3430);
DISPLAY 0.872340 (280 3430);
PAINT GREEN (280 3430);
DISPLAY INVISIBLE (280 3430);
FORCEPROP 2 LAST PATH I21
J 0
(525 3575);
DISPLAY 1.021277 (525 3575);
DISPLAY INVISIBLE (525 3575);
FORCEADD Q_RES..1
(-2125 3200);
FORCEPROP 1 LAST PART_NUMBER CS03322FB03
J 0
(-2250 3250);
DISPLAY 0.404255 (-2250 3250);
DISPLAY INVISIBLE (-2250 3250);
FORCEPROP 1 LAST TOLERANCE 1%
J 0
(-1950 3200);
DISPLAY 0.510638 (-1950 3200);
FORCEPROP 1 LAST VALUE 33.2
J 2
(-1975 3200);
DISPLAY 0.510638 (-1975 3200);
FORCEPROP 1 LAST WATTAGE 1/16W
J 2
(-2025 3275);
DISPLAY 0.404255 (-2025 3275);
FORCEPROP 1 LAST PACK_TYPE 0402LF
J 0
(-1875 3200);
DISPLAY 0.510638 (-1875 3200);
FORCEPROP 1 LAST MATERIAL CHIP
J 0
(-2250 3275);
DISPLAY 0.404255 (-2250 3275);
FORCEPROP 1 LAST $LOCATION R805
J 0
(-2375 3200);
DISPLAY 0.787234 (-2375 3200);
FORCEPROP 1 LASTPIN (-2225 3200) $PN 1
J 0
(-2213 3212);
DISPLAY 0.787234 (-2213 3212);
FORCEPROP 1 LASTPIN (-2025 3200) $PN 2
J 0
(-2063 3212);
DISPLAY 0.787234 (-2063 3212);
FORCEPROP 2 LAST CDS_LIB pure_quanta
J 0
(-2125 3200);
PAINT MONO (-2125 3200);
DISPLAY INVISIBLE (-2125 3200);
FORCEPROP 1 LAST PATH I25
J 0
(-2175 3350);
DISPLAY 0.978723 (-2175 3350);
PAINT WHITE (-2175 3350);
DISPLAY INVISIBLE (-2175 3350);
FORCEPROP 1 LAST $LOCATION R805
J 0
(-2175 3400);
DISPLAY 1.021277 (-2175 3400);
DISPLAY INVISIBLE (-2175 3400);
FORCEPROP 2 LAST CDS_LOCATION R805
J 0
(-2175 3400);
DISPLAY 1.021277 (-2175 3400);
DISPLAY INVISIBLE (-2175 3400);
FORCEPROP 2 LAST $SEC 1
J 0
(-2175 3400);
DISPLAY 0.680851 (-2175 3400);
PAINT MONO (-2175 3400);
DISPLAY INVISIBLE (-2175 3400);
FORCEPROP 2 LAST CDS_SEC 1
J 0
(-2175 3400);
DISPLAY 1.021277 (-2175 3400);
DISPLAY INVISIBLE (-2175 3400);
FORCEADD OFFPAGE..2
(325 3200);
FORCEPROP 2 LAST $XR1 239 
J 0
(634 3200);
DISPLAY 0.638298 (634 3200);
PAINT MONO (634 3200);
FORCEPROP 2 LAST $XR0 221 
J 0
(514 3200);
DISPLAY 0.638298 (514 3200);
PAINT MONO (514 3200);
FORCEPROP 2 LAST CDS_LIB standard
J 0
(325 3200);
PAINT MONO (325 3200);
DISPLAY INVISIBLE (325 3200);
FORCEPROP 1 LAST OFFPAGE TRUE
J 0
(650 3075);
DISPLAY 0.872340 (650 3075);
PAINT GREEN (650 3075);
DISPLAY INVISIBLE (650 3075);
FORCEPROP 1 LAST COMMENT_BODY TRUE
J 0
(280 3105);
DISPLAY 0.872340 (280 3105);
PAINT GREEN (280 3105);
DISPLAY INVISIBLE (280 3105);
FORCEPROP 2 LAST PATH I26
J 0
(525 3250);
DISPLAY 1.021277 (525 3250);
DISPLAY INVISIBLE (525 3250);
FORCEADD OFFPAGE..5
(-3600 3200);
FORCEPROP 2 LAST $XR0 216 
J 0
(-3855 3200);
DISPLAY 0.638298 (-3855 3200);
PAINT MONO (-3855 3200);
FORCEPROP 2 LAST CDS_LIB standard
J 0
(-3600 3200);
PAINT MONO (-3600 3200);
DISPLAY INVISIBLE (-3600 3200);
FORCEPROP 1 LAST OFFPAGE TRUE
J 0
(-3275 3075);
DISPLAY 0.872340 (-3275 3075);
PAINT GREEN (-3275 3075);
DISPLAY INVISIBLE (-3275 3075);
FORCEPROP 1 LAST COMMENT_BODY TRUE
J 0
(-3500 3125);
DISPLAY 0.872340 (-3500 3125);
PAINT PEACH (-3500 3125);
DISPLAY INVISIBLE (-3500 3125);
FORCEPROP 2 LAST PATH I29
J 0
(-3550 3275);
DISPLAY 1.021277 (-3550 3275);
DISPLAY INVISIBLE (-3550 3275);
FORCEADD Q_RES..1
(-2125 2875);
FORCEPROP 1 LAST PART_NUMBER CS03322FB03
J 0
(-2250 2925);
DISPLAY 0.404255 (-2250 2925);
DISPLAY INVISIBLE (-2250 2925);
FORCEPROP 1 LAST PACK_TYPE 0402LF
J 0
(-1875 2875);
DISPLAY 0.510638 (-1875 2875);
FORCEPROP 1 LAST TOLERANCE 1%
J 0
(-1950 2875);
DISPLAY 0.510638 (-1950 2875);
FORCEPROP 1 LAST VALUE 33.2
J 2
(-1975 2875);
DISPLAY 0.510638 (-1975 2875);
FORCEPROP 1 LAST MATERIAL CHIP
J 0
(-2250 2950);
DISPLAY 0.404255 (-2250 2950);
FORCEPROP 1 LAST WATTAGE 1/16W
J 2
(-2025 2950);
DISPLAY 0.404255 (-2025 2950);
FORCEPROP 1 LAST $LOCATION R806
J 0
(-2375 2875);
DISPLAY 0.787234 (-2375 2875);
FORCEPROP 1 LASTPIN (-2225 2875) $PN 1
J 0
(-2213 2887);
DISPLAY 0.787234 (-2213 2887);
FORCEPROP 1 LASTPIN (-2025 2875) $PN 2
J 0
(-2063 2887);
DISPLAY 0.787234 (-2063 2887);
FORCEPROP 2 LAST CDS_LIB pure_quanta
J 0
(-2125 2875);
PAINT MONO (-2125 2875);
DISPLAY INVISIBLE (-2125 2875);
FORCEPROP 1 LAST PATH I54
J 0
(-2175 3025);
DISPLAY 0.978723 (-2175 3025);
PAINT WHITE (-2175 3025);
DISPLAY INVISIBLE (-2175 3025);
FORCEPROP 1 LAST $LOCATION R806
J 0
(-2175 3075);
DISPLAY 1.021277 (-2175 3075);
DISPLAY INVISIBLE (-2175 3075);
FORCEPROP 2 LAST CDS_LOCATION R806
J 0
(-2175 3075);
DISPLAY 1.021277 (-2175 3075);
DISPLAY INVISIBLE (-2175 3075);
FORCEPROP 2 LAST $SEC 1
J 0
(-2175 3075);
DISPLAY 0.680851 (-2175 3075);
PAINT MONO (-2175 3075);
DISPLAY INVISIBLE (-2175 3075);
FORCEPROP 2 LAST CDS_SEC 1
J 0
(-2175 3075);
DISPLAY 1.021277 (-2175 3075);
DISPLAY INVISIBLE (-2175 3075);
FORCEADD OFFPAGE..2
(325 2875);
FORCEPROP 2 LAST $XR1 239 
J 0
(634 2875);
DISPLAY 0.638298 (634 2875);
PAINT MONO (634 2875);
FORCEPROP 2 LAST $XR0 221 
J 0
(514 2875);
DISPLAY 0.638298 (514 2875);
PAINT MONO (514 2875);
FORCEPROP 2 LAST CDS_LIB standard
J 0
(325 2875);
PAINT MONO (325 2875);
DISPLAY INVISIBLE (325 2875);
FORCEPROP 1 LAST OFFPAGE TRUE
J 0
(650 2750);
DISPLAY 0.872340 (650 2750);
PAINT GREEN (650 2750);
DISPLAY INVISIBLE (650 2750);
FORCEPROP 1 LAST COMMENT_BODY TRUE
J 0
(280 2780);
DISPLAY 0.872340 (280 2780);
PAINT GREEN (280 2780);
DISPLAY INVISIBLE (280 2780);
FORCEPROP 2 LAST PATH I55
J 0
(525 2925);
DISPLAY 1.021277 (525 2925);
DISPLAY INVISIBLE (525 2925);
FORCEADD OFFPAGE..5
(-3600 2875);
FORCEPROP 2 LAST $XR0 216 
J 0
(-3855 2875);
DISPLAY 0.638298 (-3855 2875);
PAINT MONO (-3855 2875);
FORCEPROP 2 LAST CDS_LIB standard
J 0
(-3600 2875);
PAINT MONO (-3600 2875);
DISPLAY INVISIBLE (-3600 2875);
FORCEPROP 1 LAST OFFPAGE TRUE
J 0
(-3275 2750);
DISPLAY 0.872340 (-3275 2750);
PAINT GREEN (-3275 2750);
DISPLAY INVISIBLE (-3275 2750);
FORCEPROP 1 LAST COMMENT_BODY TRUE
J 0
(-3500 2800);
DISPLAY 0.872340 (-3500 2800);
PAINT PEACH (-3500 2800);
DISPLAY INVISIBLE (-3500 2800);
FORCEPROP 2 LAST PATH I58
J 0
(-3550 2950);
DISPLAY 1.021277 (-3550 2950);
DISPLAY INVISIBLE (-3550 2950);
FORCEADD Q_RES..2
(-150 4125);
FORCEPROP 1 LAST PART_NUMBER CS31002FB08
J 0
(-110 3950);
DISPLAY 0.787234 (-110 3950);
DISPLAY INVISIBLE (-110 3950);
FORCEPROP 1 LAST MATERIAL CHIP
J 0
(-110 4050);
DISPLAY 0.787234 (-110 4050);
FORCEPROP 1 LAST WATTAGE 1/16W
J 0
(-110 4100);
DISPLAY 0.787234 (-110 4100);
FORCEPROP 1 LAST TOLERANCE 1%
J 0
(-105 4150);
DISPLAY 0.787234 (-105 4150);
FORCEPROP 1 LAST PACK_TYPE 0402LF
J 0
(-110 4000);
DISPLAY 0.787234 (-110 4000);
FORCEPROP 1 LAST VALUE 10K
J 0
(-105 4200);
DISPLAY 0.787234 (-105 4200);
FORCEPROP 1 LAST $LOCATION R929
J 0
(-105 4250);
DISPLAY 0.978723 (-105 4250);
FORCEPROP 1 LASTPIN (-150 4225) $PN 1
J 0
(-145 4187);
DISPLAY 0.787234 (-145 4187);
FORCEPROP 1 LASTPIN (-150 4025) $PN 2
J 0
(-145 4035);
DISPLAY 0.787234 (-145 4035);
FORCEPROP 2 LAST CDS_LIB pure_quanta
J 0
(-150 4125);
PAINT MONO (-150 4125);
DISPLAY INVISIBLE (-150 4125);
FORCEPROP 1 LAST PATH I59
J 0
(-100 4300);
DISPLAY 0.978723 (-100 4300);
PAINT WHITE (-100 4300);
DISPLAY INVISIBLE (-100 4300);
FORCEPROP 2 LAST CDS_LOCATION R929
J 0
(-100 4350);
DISPLAY 1.021277 (-100 4350);
DISPLAY INVISIBLE (-100 4350);
FORCEPROP 2 LAST $SEC 1
J 0
(-100 4350);
DISPLAY 0.680851 (-100 4350);
PAINT MONO (-100 4350);
DISPLAY INVISIBLE (-100 4350);
FORCEPROP 2 LAST CDS_SEC 1
J 0
(-100 4350);
DISPLAY 1.021277 (-100 4350);
DISPLAY INVISIBLE (-100 4350);
FORCEADD Q_RES..2
(-450 4125);
FORCEPROP 1 LAST PART_NUMBER CS31002FB08
J 0
(-410 3950);
DISPLAY 0.787234 (-410 3950);
DISPLAY INVISIBLE (-410 3950);
FORCEPROP 1 LAST VALUE 10K
J 0
(-405 4200);
DISPLAY 0.787234 (-405 4200);
FORCEPROP 1 LAST MATERIAL CHIP
J 0
(-410 4050);
DISPLAY 0.787234 (-410 4050);
FORCEPROP 1 LAST PACK_TYPE 0402LF
J 0
(-410 4000);
DISPLAY 0.787234 (-410 4000);
FORCEPROP 1 LAST WATTAGE 1/16W
J 0
(-410 4100);
DISPLAY 0.787234 (-410 4100);
FORCEPROP 1 LAST TOLERANCE 1%
J 0
(-405 4150);
DISPLAY 0.787234 (-405 4150);
FORCEPROP 1 LAST $LOCATION R928
J 0
(-405 4250);
DISPLAY 0.978723 (-405 4250);
FORCEPROP 1 LASTPIN (-450 4225) $PN 1
J 0
(-445 4187);
DISPLAY 0.787234 (-445 4187);
FORCEPROP 1 LASTPIN (-450 4025) $PN 2
J 0
(-445 4035);
DISPLAY 0.787234 (-445 4035);
FORCEPROP 2 LAST CDS_LIB pure_quanta
J 0
(-450 4125);
PAINT MONO (-450 4125);
DISPLAY INVISIBLE (-450 4125);
FORCEPROP 1 LAST PATH I60
J 0
(-400 4300);
DISPLAY 0.978723 (-400 4300);
PAINT WHITE (-400 4300);
DISPLAY INVISIBLE (-400 4300);
FORCEPROP 2 LAST CDS_LOCATION R928
J 0
(-400 4350);
DISPLAY 1.021277 (-400 4350);
DISPLAY INVISIBLE (-400 4350);
FORCEPROP 2 LAST $SEC 1
J 0
(-400 4350);
DISPLAY 0.680851 (-400 4350);
PAINT MONO (-400 4350);
DISPLAY INVISIBLE (-400 4350);
FORCEPROP 2 LAST CDS_SEC 1
J 0
(-400 4350);
DISPLAY 1.021277 (-400 4350);
DISPLAY INVISIBLE (-400 4350);
FORCEADD Q_RES..2
(-775 4125);
FORCEPROP 1 LAST PART_NUMBER CS31002FB08
J 0
(-735 3950);
DISPLAY 0.787234 (-735 3950);
DISPLAY INVISIBLE (-735 3950);
FORCEPROP 1 LAST WATTAGE 1/16W
J 0
(-735 4100);
DISPLAY 0.787234 (-735 4100);
FORCEPROP 1 LAST PACK_TYPE 0402LF
J 0
(-735 4000);
DISPLAY 0.787234 (-735 4000);
FORCEPROP 1 LAST VALUE 10K
J 0
(-730 4200);
DISPLAY 0.787234 (-730 4200);
FORCEPROP 1 LAST TOLERANCE 1%
J 0
(-730 4150);
DISPLAY 0.787234 (-730 4150);
FORCEPROP 1 LAST MATERIAL CHIP
J 0
(-735 4050);
DISPLAY 0.787234 (-735 4050);
FORCEPROP 1 LAST $LOCATION R927
J 0
(-730 4250);
DISPLAY 0.978723 (-730 4250);
FORCEPROP 1 LASTPIN (-775 4225) $PN 1
J 0
(-770 4187);
DISPLAY 0.787234 (-770 4187);
FORCEPROP 1 LASTPIN (-775 4025) $PN 2
J 0
(-770 4035);
DISPLAY 0.787234 (-770 4035);
FORCEPROP 2 LAST CDS_LIB pure_quanta
J 0
(-775 4125);
PAINT MONO (-775 4125);
DISPLAY INVISIBLE (-775 4125);
FORCEPROP 1 LAST PATH I61
J 0
(-725 4300);
DISPLAY 0.978723 (-725 4300);
PAINT WHITE (-725 4300);
DISPLAY INVISIBLE (-725 4300);
FORCEPROP 2 LAST CDS_LOCATION R927
J 0
(-725 4350);
DISPLAY 1.021277 (-725 4350);
DISPLAY INVISIBLE (-725 4350);
FORCEPROP 2 LAST $SEC 1
J 0
(-725 4350);
DISPLAY 0.680851 (-725 4350);
PAINT MONO (-725 4350);
DISPLAY INVISIBLE (-725 4350);
FORCEPROP 2 LAST CDS_SEC 1
J 0
(-725 4350);
DISPLAY 1.021277 (-725 4350);
DISPLAY INVISIBLE (-725 4350);
FORCEADD UNIVERSAL_POWER..1
(-775 4525);
FORCEPROP 3 LASTPIN (-775 4475) SIG_NAME P3V3_AUX\g
J 0
(-765 4485);
DISPLAY 0.659574 (-765 4485);
PAINT MONO (-765 4485);
DISPLAY INVISIBLE (-765 4485);
FORCEPROP 1 LAST HDL_POWER P3V3_AUX
J 1
(-775 4575);
DISPLAY 0.872340 (-775 4575);
PAINT GREEN (-775 4575);
FORCEPROP 2 LAST CDS_LIB logical_power
J 0
(-775 4525);
PAINT MONO (-775 4525);
DISPLAY INVISIBLE (-775 4525);
FORCEPROP 1 LAST PATH I62
J 0
(-725 4550);
DISPLAY 0.872340 (-725 4550);
PAINT AQUA (-725 4550);
DISPLAY INVISIBLE (-725 4550);
FORCEADD Q_RES..2
(-150 2625);
FORCEPROP 1 LAST PART_NUMBER CS24702FB06
J 0
(-110 2500);
DISPLAY 0.787234 (-110 2500);
DISPLAY INVISIBLE (-110 2500);
FORCEPROP 1 LAST TOLERANCE 1%
J 0
(-105 2650);
DISPLAY 0.787234 (-105 2650);
FORCEPROP 1 LAST PACK_TYPE 0402LF
J 0
(-110 2450);
DISPLAY 0.787234 (-110 2450);
FORCEPROP 1 LAST MATERIAL CHIP
J 0
(-110 2550);
DISPLAY 0.787234 (-110 2550);
FORCEPROP 1 LAST WATTAGE 1/16W
J 0
(-110 2600);
DISPLAY 0.787234 (-110 2600);
FORCEPROP 1 LAST VALUE 4.7K
J 0
(-105 2700);
DISPLAY 0.787234 (-105 2700);
FORCEPROP 1 LAST $LOCATION R930
J 0
(-105 2750);
DISPLAY 0.978723 (-105 2750);
FORCEPROP 1 LASTPIN (-150 2725) $PN 1
J 0
(-145 2687);
DISPLAY 0.787234 (-145 2687);
FORCEPROP 1 LASTPIN (-150 2525) $PN 2
J 0
(-145 2535);
DISPLAY 0.787234 (-145 2535);
FORCEPROP 2 LAST CDS_LIB pure_quanta
J 0
(-150 2625);
PAINT MONO (-150 2625);
DISPLAY INVISIBLE (-150 2625);
FORCEPROP 1 LAST PATH I63
J 0
(-100 2800);
DISPLAY 0.978723 (-100 2800);
PAINT WHITE (-100 2800);
DISPLAY INVISIBLE (-100 2800);
FORCEPROP 2 LAST CDS_LOCATION R930
J 0
(-100 2850);
DISPLAY 1.021277 (-100 2850);
DISPLAY INVISIBLE (-100 2850);
FORCEPROP 2 LAST $SEC 1
J 0
(-100 2850);
DISPLAY 0.680851 (-100 2850);
PAINT MONO (-100 2850);
DISPLAY INVISIBLE (-100 2850);
FORCEPROP 2 LAST CDS_SEC 1
J 0
(-100 2850);
DISPLAY 1.021277 (-100 2850);
DISPLAY INVISIBLE (-100 2850);
FORCEADD UNIVERSAL_GND..1
(-150 2400);
FORCEPROP 3 LASTPIN (-150 2450) SIG_NAME GND\g
J 0
(-140 2460);
DISPLAY 0.659574 (-140 2460);
PAINT MONO (-140 2460);
DISPLAY INVISIBLE (-140 2460);
FORCEPROP 2 LAST CDS_LIB logical_power
J 0
(-150 2400);
PAINT MONO (-150 2400);
DISPLAY INVISIBLE (-150 2400);
FORCEPROP 1 LAST HDL_POWER GND
J 1
(-125 2325);
DISPLAY 0.872340 (-125 2325);
PAINT GREEN (-125 2325);
DISPLAY INVISIBLE (-125 2325);
FORCEPROP 1 LAST PATH I64
J 0
(-75 2400);
DISPLAY 0.872340 (-75 2400);
PAINT AQUA (-75 2400);
DISPLAY INVISIBLE (-75 2400);
FORCEADD OFFPAGE..1
(-3600 3525);
FORCEPROP 2 LAST $XR1 220 
J 0
(-3972 3525);
DISPLAY 0.638298 (-3972 3525);
PAINT MONO (-3972 3525);
FORCEPROP 2 LAST $XR0 216 
J 0
(-3852 3525);
DISPLAY 0.638298 (-3852 3525);
PAINT MONO (-3852 3525);
FORCEPROP 2 LAST CDS_LIB standard
J 0
(-3600 3525);
PAINT MONO (-3600 3525);
DISPLAY INVISIBLE (-3600 3525);
FORCEPROP 1 LAST OFFPAGE TRUE
J 0
(-3275 3400);
DISPLAY 0.872340 (-3275 3400);
PAINT GREEN (-3275 3400);
DISPLAY INVISIBLE (-3275 3400);
FORCEPROP 1 LAST COMMENT_BODY TRUE
J 0
(-3475 3425);
DISPLAY 0.872340 (-3475 3425);
PAINT GREEN (-3475 3425);
DISPLAY INVISIBLE (-3475 3425);
FORCEPROP 2 LAST PATH I65
J 0
(-3550 3600);
DISPLAY 1.021277 (-3550 3600);
DISPLAY INVISIBLE (-3550 3600);
FORCEADD OFFPAGE..4
(325 3850);
FORCEPROP 2 LAST $XR1 239 
J 0
(631 3850);
DISPLAY 0.638298 (631 3850);
PAINT MONO (631 3850);
FORCEPROP 2 LAST $XR0 221 
J 0
(511 3850);
DISPLAY 0.638298 (511 3850);
PAINT MONO (511 3850);
FORCEPROP 2 LAST CDS_LIB standard
J 0
(325 3850);
PAINT MONO (325 3850);
DISPLAY INVISIBLE (325 3850);
FORCEPROP 1 LAST OFFPAGE TRUE
J 0
(650 3725);
DISPLAY 0.872340 (650 3725);
PAINT GREEN (650 3725);
DISPLAY INVISIBLE (650 3725);
FORCEPROP 1 LAST COMMENT_BODY TRUE
J 0
(300 3750);
DISPLAY 0.872340 (300 3750);
PAINT PEACH (300 3750);
DISPLAY INVISIBLE (300 3750);
FORCEPROP 2 LAST PATH I67
J 0
(500 3925);
DISPLAY 1.021277 (500 3925);
DISPLAY INVISIBLE (500 3925);
FORCEADD OFFPAGE..2
(2775 1225);
FORCEPROP 2 LAST $XR0 216 
J 0
(2964 1225);
DISPLAY 0.638298 (2964 1225);
PAINT MONO (2964 1225);
FORCEPROP 2 LAST CDS_LIB standard
J 0
(2775 1225);
PAINT MONO (2775 1225);
DISPLAY INVISIBLE (2775 1225);
FORCEPROP 1 LAST OFFPAGE TRUE
J 0
(3100 1100);
DISPLAY 0.872340 (3100 1100);
DISPLAY INVISIBLE (3100 1100);
FORCEPROP 1 LAST COMMENT_BODY TRUE
J 0
(2730 1130);
DISPLAY 0.872340 (2730 1130);
PAINT GREEN (2730 1130);
DISPLAY INVISIBLE (2730 1130);
FORCEPROP 2 LAST PATH I72
J 0
(3125 1275);
DISPLAY 1.021277 (3125 1275);
DISPLAY INVISIBLE (3125 1275);
FORCEADD Q_RES..2
(1650 1500);
FORCEPROP 1 LAST PART_NUMBER CS31002FB08
J 0
(1690 1375);
DISPLAY 0.638298 (1690 1375);
DISPLAY INVISIBLE (1690 1375);
FORCEPROP 1 LAST WATTAGE 1/16W
J 0
(1690 1475);
DISPLAY 0.787234 (1690 1475);
FORCEPROP 1 LAST VALUE 10K
J 0
(1695 1575);
DISPLAY 0.787234 (1695 1575);
FORCEPROP 1 LAST PACK_TYPE 0402LF
J 0
(1690 1325);
DISPLAY 0.787234 (1690 1325);
FORCEPROP 1 LAST MATERIAL CHIP
J 0
(1690 1425);
DISPLAY 0.787234 (1690 1425);
FORCEPROP 1 LAST TOLERANCE 1%
J 0
(1695 1525);
DISPLAY 0.787234 (1695 1525);
FORCEPROP 1 LAST $LOCATION R919
J 0
(1695 1625);
DISPLAY 0.978723 (1695 1625);
FORCEPROP 1 LASTPIN (1650 1600) $PN 1
J 0
(1655 1562);
DISPLAY 0.787234 (1655 1562);
FORCEPROP 1 LASTPIN (1650 1400) $PN 2
J 0
(1655 1410);
DISPLAY 0.787234 (1655 1410);
FORCEPROP 2 LAST CDS_LIB pure_quanta
J 0
(1650 1500);
PAINT MONO (1650 1500);
DISPLAY INVISIBLE (1650 1500);
FORCEPROP 1 LAST PATH I75
J 0
(1700 1675);
DISPLAY 0.978723 (1700 1675);
PAINT WHITE (1700 1675);
DISPLAY INVISIBLE (1700 1675);
FORCEPROP 2 LAST CDS_LOCATION R919
J 0
(1700 1725);
DISPLAY 1.021277 (1700 1725);
DISPLAY INVISIBLE (1700 1725);
FORCEPROP 2 LAST $SEC 1
J 0
(1700 1725);
DISPLAY 0.680851 (1700 1725);
PAINT MONO (1700 1725);
DISPLAY INVISIBLE (1700 1725);
FORCEPROP 2 LAST CDS_SEC 1
J 0
(1700 1725);
DISPLAY 1.021277 (1700 1725);
DISPLAY INVISIBLE (1700 1725);
FORCEADD Q_RES..2
(1650 975);
FORCEPROP 1 LAST PART_NUMBER CS21002FB06
J 0
(1690 850);
DISPLAY 0.638298 (1690 850);
DISPLAY INVISIBLE (1690 850);
FORCEPROP 1 LAST PACK_TYPE 0402LF
J 0
(1690 800);
DISPLAY 0.787234 (1690 800);
FORCEPROP 1 LAST MATERIAL EMPTY
J 0
(1690 900);
DISPLAY 0.787234 (1690 900);
PAINT RED (1690 900);
FORCEPROP 1 LAST TOLERANCE 1%
J 0
(1695 1000);
DISPLAY 0.787234 (1695 1000);
FORCEPROP 1 LAST VALUE 1K
J 0
(1695 1050);
DISPLAY 0.787234 (1695 1050);
FORCEPROP 1 LAST WATTAGE 1/16W
J 0
(1690 950);
DISPLAY 0.787234 (1690 950);
FORCEPROP 1 LAST $LOCATION R920
J 0
(1695 1100);
DISPLAY 0.978723 (1695 1100);
FORCEPROP 1 LASTPIN (1650 1075) $PN 1
J 0
(1655 1037);
DISPLAY 0.787234 (1655 1037);
FORCEPROP 1 LASTPIN (1650 875) $PN 2
J 0
(1655 885);
DISPLAY 0.787234 (1655 885);
FORCEPROP 2 LAST CDS_LIB pure_quanta
J 0
(1650 975);
PAINT MONO (1650 975);
DISPLAY INVISIBLE (1650 975);
FORCEPROP 1 LAST PATH I76
J 0
(1700 1150);
DISPLAY 0.978723 (1700 1150);
PAINT WHITE (1700 1150);
DISPLAY INVISIBLE (1700 1150);
FORCEPROP 2 LAST CDS_LOCATION R920
J 0
(1700 1200);
DISPLAY 1.021277 (1700 1200);
DISPLAY INVISIBLE (1700 1200);
FORCEPROP 2 LAST $SEC 1
J 0
(1700 1200);
DISPLAY 0.680851 (1700 1200);
PAINT MONO (1700 1200);
DISPLAY INVISIBLE (1700 1200);
FORCEPROP 2 LAST CDS_SEC 1
J 0
(1700 1200);
DISPLAY 1.021277 (1700 1200);
DISPLAY INVISIBLE (1700 1200);
FORCEADD UNIVERSAL_POWER..1
(1650 1825);
FORCEPROP 3 LASTPIN (1650 1775) SIG_NAME P3V3_AUX\g
J 0
(1660 1785);
DISPLAY 0.659574 (1660 1785);
PAINT MONO (1660 1785);
DISPLAY INVISIBLE (1660 1785);
FORCEPROP 1 LAST HDL_POWER P3V3_AUX
J 1
(1650 1875);
DISPLAY 0.872340 (1650 1875);
PAINT GREEN (1650 1875);
FORCEPROP 2 LAST CDS_LIB logical_power
J 0
(1650 1825);
PAINT MONO (1650 1825);
DISPLAY INVISIBLE (1650 1825);
FORCEPROP 1 LAST PATH I77
J 0
(1700 1850);
DISPLAY 0.872340 (1700 1850);
PAINT AQUA (1700 1850);
DISPLAY INVISIBLE (1700 1850);
FORCEADD UNIVERSAL_GND..1
(1650 625);
FORCEPROP 3 LASTPIN (1650 675) SIG_NAME GND\g
J 0
(1660 685);
DISPLAY 0.659574 (1660 685);
PAINT MONO (1660 685);
DISPLAY INVISIBLE (1660 685);
FORCEPROP 2 LAST CDS_LIB logical_power
J 0
(1650 625);
PAINT MONO (1650 625);
DISPLAY INVISIBLE (1650 625);
FORCEPROP 1 LAST HDL_POWER GND
J 1
(1675 550);
DISPLAY 0.872340 (1675 550);
PAINT GREEN (1675 550);
DISPLAY INVISIBLE (1675 550);
FORCEPROP 1 LAST PATH I78
J 0
(1725 625);
DISPLAY 0.872340 (1725 625);
PAINT AQUA (1725 625);
DISPLAY INVISIBLE (1725 625);
FORCEPROP 2 LAST ROOM IO_SLOT
J 1
(1425 700);
DISPLAY 0.744681 (1425 700);
DISPLAY INVISIBLE (1425 700);
FORCEADD CONN8_210HP1080BR1..1
(-425 750);
FORCEPROP 1 LAST PART_NUMBER DFHD08MS392
J 0
(-490 1069);
DISPLAY 0.723404 (-490 1069);
PAINT GREEN (-490 1069);
DISPLAY INVISIBLE (-490 1069);
FORCEPROP 1 LAST MATERIAL IO
J 0
(-490 980);
DISPLAY 0.723404 (-490 980);
PAINT GREEN (-490 980);
FORCEPROP 2 LAST PART_TYPE THLF
J 0
(-475 1250);
DISPLAY 1.021277 (-475 1250);
FORCEPROP 2 LAST VALUE CONN8_210-HP1-080BR1
J 0
(-475 1200);
DISPLAY 1.021277 (-475 1200);
FORCEPROP 1 LAST LOCATION J43
J 0
(-490 1153);
DISPLAY 0.723404 (-490 1153);
PAINT GREEN (-490 1153);
FORCEPROP 0 LASTPIN (-625 925) $PN 1
J 2
(-635 935);
DISPLAY 0.680851 (-635 935);
PAINT MONO (-635 935);
FORCEPROP 0 LASTPIN (-625 875) $PN 2
J 2
(-635 885);
DISPLAY 0.680851 (-635 885);
PAINT MONO (-635 885);
FORCEPROP 0 LASTPIN (-625 825) $PN 3
J 2
(-635 835);
DISPLAY 0.680851 (-635 835);
PAINT MONO (-635 835);
FORCEPROP 0 LASTPIN (-625 775) $PN 4
J 2
(-635 785);
DISPLAY 0.680851 (-635 785);
PAINT MONO (-635 785);
FORCEPROP 0 LASTPIN (-625 725) $PN 5
J 2
(-635 735);
DISPLAY 0.680851 (-635 735);
PAINT MONO (-635 735);
FORCEPROP 0 LASTPIN (-625 675) $PN 6
J 2
(-635 685);
DISPLAY 0.680851 (-635 685);
PAINT MONO (-635 685);
FORCEPROP 0 LASTPIN (-625 625) $PN 7
J 2
(-635 635);
DISPLAY 0.680851 (-635 635);
PAINT MONO (-635 635);
FORCEPROP 0 LASTPIN (-625 575) $PN 8
J 2
(-635 585);
DISPLAY 0.680851 (-635 585);
PAINT MONO (-635 585);
FORCEPROP 2 LAST CDS_LIB pure_quanta
J 0
(-425 750);
DISPLAY INVISIBLE (-425 750);
FORCEPROP 1 LAST CDS_LMAN_SYM_OUTLINE -50,225,50,-225
J 0
(-425 750);
DISPLAY 0.468085 (-425 750);
PAINT GREEN (-425 750);
DISPLAY INVISIBLE (-425 750);
FORCEPROP 1 LAST NEEDS_NO_SIZE True
J 0
(-425 750);
DISPLAY 0.723404 (-425 750);
PAINT GREEN (-425 750);
DISPLAY INVISIBLE (-425 750);
FORCEPROP 1 LAST PATH I79
J 0
(-425 750);
DISPLAY 0.723404 (-425 750);
PAINT GREEN (-425 750);
DISPLAY INVISIBLE (-425 750);
FORCEPROP 0 LAST $SEC 1
J 0
(-475 1300);
DISPLAY 0.680851 (-475 1300);
PAINT MONO (-475 1300);
DISPLAY INVISIBLE (-475 1300);
FORCEPROP 0 LAST CDS_SEC 1
J 0
(-475 1300);
DISPLAY 1.021277 (-475 1300);
DISPLAY INVISIBLE (-475 1300);
FORCEADD OFFPAGE..5
(-1650 575);
FORCEPROP 2 LAST $XR1 239 
J 0
(-2055 575);
DISPLAY 0.638298 (-2055 575);
PAINT MONO (-2055 575);
FORCEPROP 2 LAST $XR0 221 
J 0
(-1935 575);
DISPLAY 0.638298 (-1935 575);
PAINT MONO (-1935 575);
FORCEPROP 2 LAST CDS_LIB standard
J 0
(-1650 575);
PAINT MONO (-1650 575);
DISPLAY INVISIBLE (-1650 575);
FORCEPROP 1 LAST OFFPAGE TRUE
J 0
(-1325 450);
DISPLAY 0.872340 (-1325 450);
PAINT GREEN (-1325 450);
DISPLAY INVISIBLE (-1325 450);
FORCEPROP 1 LAST COMMENT_BODY TRUE
J 0
(-1550 500);
DISPLAY 0.872340 (-1550 500);
PAINT PEACH (-1550 500);
DISPLAY INVISIBLE (-1550 500);
FORCEPROP 2 LAST PATH I81
J 0
(-1900 625);
DISPLAY 1.021277 (-1900 625);
DISPLAY INVISIBLE (-1900 625);
FORCEADD OFFPAGE..1
(-1650 875);
FORCEPROP 2 LAST $XR1 239 
J 0
(-2022 875);
DISPLAY 0.638298 (-2022 875);
PAINT MONO (-2022 875);
FORCEPROP 2 LAST $XR0 221 
J 0
(-1902 875);
DISPLAY 0.638298 (-1902 875);
PAINT MONO (-1902 875);
FORCEPROP 2 LAST CDS_LIB standard
J 0
(-1650 875);
PAINT MONO (-1650 875);
DISPLAY INVISIBLE (-1650 875);
FORCEPROP 1 LAST OFFPAGE TRUE
J 0
(-1325 750);
DISPLAY 0.872340 (-1325 750);
PAINT GREEN (-1325 750);
DISPLAY INVISIBLE (-1325 750);
FORCEPROP 1 LAST COMMENT_BODY TRUE
J 0
(-1525 775);
DISPLAY 0.872340 (-1525 775);
PAINT GREEN (-1525 775);
DISPLAY INVISIBLE (-1525 775);
FORCEPROP 2 LAST PATH I82
J 0
(-1925 925);
DISPLAY 1.021277 (-1925 925);
DISPLAY INVISIBLE (-1925 925);
FORCEADD OFFPAGE..5
(-1650 675);
FORCEPROP 2 LAST $XR1 239 
J 0
(-2055 675);
DISPLAY 0.638298 (-2055 675);
PAINT MONO (-2055 675);
FORCEPROP 2 LAST $XR0 221 
J 0
(-1935 675);
DISPLAY 0.638298 (-1935 675);
PAINT MONO (-1935 675);
FORCEPROP 2 LAST CDS_LIB standard
J 0
(-1650 675);
PAINT MONO (-1650 675);
DISPLAY INVISIBLE (-1650 675);
FORCEPROP 1 LAST OFFPAGE TRUE
J 0
(-1325 550);
DISPLAY 0.872340 (-1325 550);
PAINT GREEN (-1325 550);
DISPLAY INVISIBLE (-1325 550);
FORCEPROP 1 LAST COMMENT_BODY TRUE
J 0
(-1550 600);
DISPLAY 0.872340 (-1550 600);
PAINT PEACH (-1550 600);
DISPLAY INVISIBLE (-1550 600);
FORCEPROP 2 LAST PATH I83
J 0
(-1900 725);
DISPLAY 1.021277 (-1900 725);
DISPLAY INVISIBLE (-1900 725);
FORCEADD OFFPAGE..5
(-1650 825);
FORCEPROP 2 LAST $XR1 221 
J 0
(-2055 825);
DISPLAY 0.638298 (-2055 825);
PAINT MONO (-2055 825);
FORCEPROP 2 LAST $XR0 239 
J 0
(-1935 825);
DISPLAY 0.638298 (-1935 825);
PAINT MONO (-1935 825);
FORCEPROP 2 LAST CDS_LIB standard
J 0
(-1650 825);
PAINT MONO (-1650 825);
DISPLAY INVISIBLE (-1650 825);
FORCEPROP 1 LAST OFFPAGE TRUE
J 0
(-1325 700);
DISPLAY 0.872340 (-1325 700);
PAINT GREEN (-1325 700);
DISPLAY INVISIBLE (-1325 700);
FORCEPROP 1 LAST COMMENT_BODY TRUE
J 0
(-1550 750);
DISPLAY 0.872340 (-1550 750);
PAINT PEACH (-1550 750);
DISPLAY INVISIBLE (-1550 750);
FORCEPROP 2 LAST PATH I84
J 0
(-1900 875);
DISPLAY 1.021277 (-1900 875);
DISPLAY INVISIBLE (-1900 875);
FORCEADD Q_CAP..1
R 2
(-1200 1400);
FORCEPROP 1 LAST PART_NUMBER CH4104K1B00
J 2
(-1250 1250);
DISPLAY 0.510638 (-1250 1250);
DISPLAY INVISIBLE (-1250 1250);
FORCEPROP 1 LAST VALUE 0.1UF
J 2
(-1250 1450);
DISPLAY 0.510638 (-1250 1450);
FORCEPROP 1 LAST VOLTAGE 25V
J 2
(-1250 1400);
DISPLAY 0.510638 (-1250 1400);
FORCEPROP 1 LAST MATERIAL X7R
J 2
(-1250 1300);
DISPLAY 0.510638 (-1250 1300);
FORCEPROP 1 LAST TOLERANCE 10%
J 2
(-1250 1350);
DISPLAY 0.510638 (-1250 1350);
FORCEPROP 1 LAST PACK_TYPE 0402
J 2
(-1250 1200);
DISPLAY 0.510638 (-1250 1200);
FORCEPROP 1 LAST $LOCATION C554
J 2
(-1250 1500);
DISPLAY 0.978723 (-1250 1500);
FORCEPROP 1 LASTPIN (-1200 1500) $PN 1
J 2
(-1210 1480);
DISPLAY 0.787234 (-1210 1480);
FORCEPROP 1 LASTPIN (-1200 1300) $PN 2
J 2
(-1210 1280);
DISPLAY 0.787234 (-1210 1280);
FORCEPROP 2 LAST CDS_LIB pure_quanta
J 0
(-1200 1400);
PAINT MONO (-1200 1400);
DISPLAY INVISIBLE (-1200 1400);
FORCEPROP 1 LAST PATH I86
J 2
(-1250 1550);
DISPLAY 0.978723 (-1250 1550);
PAINT WHITE (-1250 1550);
DISPLAY INVISIBLE (-1250 1550);
FORCEPROP 1 LAST $LOCATION C554
J 2
(-1250 1600);
DISPLAY 1.021277 (-1250 1600);
DISPLAY INVISIBLE (-1250 1600);
FORCEPROP 2 LAST CDS_LOCATION C554
J 0
(-1250 1600);
DISPLAY 1.021277 (-1250 1600);
DISPLAY INVISIBLE (-1250 1600);
FORCEPROP 2 LAST $SEC 1
J 2
(-1250 1600);
DISPLAY 0.680851 (-1250 1600);
PAINT MONO (-1250 1600);
DISPLAY INVISIBLE (-1250 1600);
FORCEPROP 2 LAST CDS_SEC 1
J 2
(-1250 1600);
DISPLAY 1.021277 (-1250 1600);
DISPLAY INVISIBLE (-1250 1600);
FORCEADD Q_CAP..1
(-1075 1400);
FORCEPROP 1 LAST PART_NUMBER CH6104KEA00
J 0
(-1025 1250);
DISPLAY 0.510638 (-1025 1250);
DISPLAY INVISIBLE (-1025 1250);
FORCEPROP 1 LAST VALUE 10UF
J 0
(-1025 1450);
DISPLAY 0.510638 (-1025 1450);
FORCEPROP 1 LAST PACK_TYPE C0805
J 0
(-1025 1200);
DISPLAY 0.510638 (-1025 1200);
FORCEPROP 1 LAST VOLTAGE 25V
J 0
(-1025 1400);
DISPLAY 0.510638 (-1025 1400);
FORCEPROP 1 LAST TOLERANCE 10%
J 0
(-1025 1350);
DISPLAY 0.510638 (-1025 1350);
FORCEPROP 1 LAST MATERIAL X6S
J 0
(-1025 1300);
DISPLAY 0.510638 (-1025 1300);
FORCEPROP 1 LAST $LOCATION C563
J 0
(-1025 1500);
DISPLAY 0.978723 (-1025 1500);
FORCEPROP 1 LASTPIN (-1075 1500) $PN 1
J 0
(-1065 1480);
DISPLAY 0.787234 (-1065 1480);
FORCEPROP 1 LASTPIN (-1075 1300) $PN 2
J 0
(-1065 1280);
DISPLAY 0.787234 (-1065 1280);
FORCEPROP 2 LAST CDS_LIB pure_quanta
J 0
(-1075 1400);
PAINT MONO (-1075 1400);
DISPLAY INVISIBLE (-1075 1400);
FORCEPROP 1 LAST PATH I88
J 0
(-1025 1550);
DISPLAY 0.978723 (-1025 1550);
PAINT WHITE (-1025 1550);
DISPLAY INVISIBLE (-1025 1550);
FORCEPROP 2 LAST CDS_LOCATION C563
J 0
(-1025 1600);
DISPLAY 1.021277 (-1025 1600);
DISPLAY INVISIBLE (-1025 1600);
FORCEPROP 2 LAST $SEC 1
J 0
(-1025 1600);
DISPLAY 0.680851 (-1025 1600);
PAINT MONO (-1025 1600);
DISPLAY INVISIBLE (-1025 1600);
FORCEPROP 2 LAST CDS_SEC 1
J 0
(-1025 1600);
DISPLAY 1.021277 (-1025 1600);
DISPLAY INVISIBLE (-1025 1600);
FORCEADD UNIVERSAL_GND..1
(-1200 1075);
FORCEPROP 3 LASTPIN (-1200 1125) SIG_NAME GND\g
J 0
(-1190 1135);
DISPLAY 0.659574 (-1190 1135);
PAINT MONO (-1190 1135);
DISPLAY INVISIBLE (-1190 1135);
FORCEPROP 2 LAST CDS_LIB logical_power
J 0
(-1200 1075);
PAINT MONO (-1200 1075);
DISPLAY INVISIBLE (-1200 1075);
FORCEPROP 1 LAST HDL_POWER GND
J 1
(-1175 1000);
DISPLAY 0.872340 (-1175 1000);
PAINT GREEN (-1175 1000);
DISPLAY INVISIBLE (-1175 1000);
FORCEPROP 1 LAST PATH I89
J 0
(-1125 1075);
DISPLAY 0.872340 (-1125 1075);
PAINT AQUA (-1125 1075);
DISPLAY INVISIBLE (-1125 1075);
FORCEADD UNIVERSAL_GND..1
(-750 225);
FORCEPROP 3 LASTPIN (-750 275) SIG_NAME GND\g
J 0
(-740 285);
DISPLAY 0.659574 (-740 285);
PAINT MONO (-740 285);
DISPLAY INVISIBLE (-740 285);
FORCEPROP 2 LAST CDS_LIB logical_power
J 0
(-750 225);
PAINT MONO (-750 225);
DISPLAY INVISIBLE (-750 225);
FORCEPROP 1 LAST HDL_POWER GND
J 1
(-725 150);
DISPLAY 0.872340 (-725 150);
PAINT GREEN (-725 150);
DISPLAY INVISIBLE (-725 150);
FORCEPROP 1 LAST PATH I90
J 0
(-675 225);
DISPLAY 0.872340 (-675 225);
PAINT AQUA (-675 225);
DISPLAY INVISIBLE (-675 225);
FORCEADD SCHOTTKY_12..1
(-1925 1575);
FORCEPROP 1 LAST PART_NUMBER BC005819Z40
J 0
(-2000 1700);
DISPLAY 0.723404 (-2000 1700);
PAINT GREEN (-2000 1700);
DISPLAY INVISIBLE (-2000 1700);
FORCEPROP 1 LAST MATERIAL IC
J 0
(-2000 1650);
DISPLAY 0.723404 (-2000 1650);
PAINT GREEN (-2000 1650);
FORCEPROP 2 LAST VALUE 1N5819HW
J 0
(-2000 1800);
DISPLAY 1.021277 (-2000 1800);
FORCEPROP 2 LAST PART_TYPE SMLF
J 0
(-2000 1850);
DISPLAY 1.021277 (-2000 1850);
FORCEPROP 1 LAST $LOCATION D141
J 0
(-2000 1750);
DISPLAY 0.723404 (-2000 1750);
PAINT GREEN (-2000 1750);
FORCEPROP 0 LASTPIN (-2050 1575) $PN 1
J 2
(-2060 1585);
DISPLAY 0.680851 (-2060 1585);
PAINT MONO (-2060 1585);
FORCEPROP 0 LASTPIN (-1800 1575) $PN 2
J 0
(-1790 1585);
DISPLAY 0.680851 (-1790 1585);
PAINT MONO (-1790 1585);
FORCEPROP 2 LAST CDS_LIB pure_quanta
J 0
(-1925 1575);
DISPLAY INVISIBLE (-1925 1575);
FORCEPROP 1 LAST NEEDS_NO_SIZE TRUE
J 0
(-1850 1525);
DISPLAY 0.468085 (-1850 1525);
PAINT GREEN (-1850 1525);
DISPLAY INVISIBLE (-1850 1525);
FORCEPROP 1 LAST CDS_LMAN_SYM_OUTLINE -75,50,75,-50
J 0
(-1925 1575);
DISPLAY 0.468085 (-1925 1575);
PAINT GREEN (-1925 1575);
DISPLAY INVISIBLE (-1925 1575);
FORCEPROP 1 LAST PATH I91
J 0
(-1925 1575);
DISPLAY 0.723404 (-1925 1575);
PAINT GREEN (-1925 1575);
DISPLAY INVISIBLE (-1925 1575);
FORCEPROP 0 LAST CDS_LOCATION D141
J 0
(-2000 1900);
DISPLAY 1.021277 (-2000 1900);
DISPLAY INVISIBLE (-2000 1900);
FORCEPROP 0 LAST $SEC 1
J 0
(-2000 1900);
DISPLAY 0.680851 (-2000 1900);
PAINT MONO (-2000 1900);
DISPLAY INVISIBLE (-2000 1900);
FORCEPROP 0 LAST CDS_SEC 1
J 0
(-2000 1900);
DISPLAY 1.021277 (-2000 1900);
DISPLAY INVISIBLE (-2000 1900);
FORCEADD UNIVERSAL_POWER..1
(-2250 1725);
FORCEPROP 3 LASTPIN (-2250 1675) SIG_NAME P3V3_AUX\g
J 0
(-2240 1685);
DISPLAY 0.659574 (-2240 1685);
PAINT MONO (-2240 1685);
DISPLAY INVISIBLE (-2240 1685);
FORCEPROP 1 LAST HDL_POWER P3V3_AUX
J 1
(-2250 1775);
DISPLAY 0.872340 (-2250 1775);
PAINT GREEN (-2250 1775);
FORCEPROP 2 LAST CDS_LIB logical_power
J 0
(-2250 1725);
PAINT MONO (-2250 1725);
DISPLAY INVISIBLE (-2250 1725);
FORCEPROP 1 LAST PATH I92
J 0
(-2200 1750);
DISPLAY 0.872340 (-2200 1750);
PAINT AQUA (-2200 1750);
DISPLAY INVISIBLE (-2200 1750);
FORCEADD DNS..2
(1655 945);
PAINT RED (1655 945);
FORCEPROP 2 LAST CDS_LIB mstr_misc
J 0
(1655 945);
PAINT MONO (1655 945);
DISPLAY INVISIBLE (1655 945);
FORCEPROP 1 LAST COMMENT_BODY TRUE
J 0
(1655 945);
DISPLAY INVISIBLE (1655 945);
FORCEADD QUANTA_TITLE_BLOCK_C..1
(4625 -1475);
FORCEPROP 0 LAST CDS_CON_LAST_MODIFIED Fri Aug 25 14:03:42 2023
J 0
(2740 -1460);
PAINT MONO (2740 -1460);
DISPLAY INVISIBLE (2740 -1460);
FORCEPROP 2 LAST CUSTOM_TXT_CDS <XR_PAGE_TITLE>
J 0
(-3265 3775);
DISPLAY 0.638298 (-3265 3775);
PAINT PINK (-3265 3775);
DISPLAY INVISIBLE (-3265 3775);
FORCEPROP 2 LAST CUSTOM_TXT_CDS <CON_LAST_MODIFIED>
J 0
(2740 -1460);
DISPLAY 0.978723 (2740 -1460);
FORCEPROP 2 LAST CUSTOM_TXT_CDS <NAME_1>
J 0
(1450 -1300);
FORCEPROP 2 LAST CUSTOM_TXT_CDS <Q_NUMBER>
J 0
(3222 -1372);
DISPLAY 1.212766 (3222 -1372);
FORCEPROP 2 LAST CUSTOM_TXT_CDS <Q_PROJ>
J 0
(2243 -1373);
DISPLAY 1.212766 (2243 -1373);
FORCEPROP 2 LAST CUSTOM_TXT_CDS <Q_REV>
J 0
(4441 -1372);
DISPLAY 1.212766 (4441 -1372);
FORCEPROP 2 LAST CUSTOM_TXT_CDS <CON_PAGE_NUM> OF <CON_TOTAL_PAGES>
J 0
(4179 -1457);
DISPLAY 0.978723 (4179 -1457);
FORCEPROP 2 LAST CUSTOM_TXT_CDS <NAME_2>
J 0
(1450 -1425);
FORCEPROP 1 LAST Q_TITLE MAIN FPGA / PFR - JTAG
J 0
(-4666 -1449);
DISPLAY 2.446809 (-4666 -1449);
PAINT GREEN (-4666 -1449);
FORCEPROP 1 LAST Q_DEPT 
J 1
(862 -1426);
DISPLAY 1.957447 (862 -1426);
PAINT GREEN (862 -1426);
FORCEPROP 2 LAST CDS_XR_PAGE_TITLE CR-221 : @S9S_MB_2U_LIB.S9S_MB_2U(SCH_1):PAGE221
J 0
(-3265 3775);
DISPLAY 0.638298 (-3265 3775);
PAINT PINK (-3265 3775);
DISPLAY INVISIBLE (-3265 3775);
FORCEPROP 1 LAST COMMENT_BODY TRUE
J 0
(4637 -1488);
DISPLAY 0.978723 (4637 -1488);
PAINT GREEN (4637 -1488);
DISPLAY INVISIBLE (4637 -1488);
FORCEPROP 2 LAST PAGE_BORDER TRUE
J 0
(-3265 3775);
DISPLAY 0.638298 (-3265 3775);
PAINT PINK (-3265 3775);
DISPLAY INVISIBLE (-3265 3775);
FORCEPROP 1 LAST CDS_LMAN_SYM_OUTLINE -9475,6775,100,-125
J 0
(4625 -1475);
DISPLAY 0.468085 (4625 -1475);
PAINT GREEN (4625 -1475);
DISPLAY INVISIBLE (4625 -1475);
FORCEPROP 2 LAST CDS_LIB pure_quanta
J 0
(4625 -1475);
PAINT MONO (4625 -1475);
DISPLAY INVISIBLE (4625 -1475);
WIRE 16 -1 (-775 4475)(-775 4350);
WIRE 16 -1 (1650 1775)(1650 1600);
WIRE 16 -1 (-2250 1575)(-2250 1675);
WIRE 16 -1 (-2050 1575)(-2250 1575);
WIRE 16 -1 (-150 2525)(-150 2450);
WIRE 16 -1 (1650 675)(1650 875);
WIRE 16 -1 (-750 275)(-750 625);
WIRE 16 -1 (-1200 1175)(-1200 1125);
WIRE 16 -1 (-1075 1175)(-1200 1175);
WIRE 16 -1 (-1200 1300)(-1200 1175);
WIRE 16 -1 (-750 925)(-625 925);
WIRE 16 -1 (-750 1575)(-750 925);
WIRE 16 -1 (-1075 1500)(-1075 1575);
WIRE 16 -1 (-750 1575)(-1075 1575);
WIRE 16 -1 (-1200 1575)(-1200 1500);
WIRE 16 -1 (-1075 1575)(-1200 1575);
WIRE 16 -1 (-1800 1575)(-1200 1575);
FORCEPROP 2 LAST SIG_NAME P3V3_AUX_BMC_D
J 0
(-1500 1585);
DISPLAY 0.808511 (-1500 1585);
PAINT WHITE (-1500 1585);
WIRE 16 -1 (-625 875)(-1600 875);
FORCEPROP 2 LAST SIG_NAME JTAG_BMC_PLD_TDO
J 0
(-1385 885);
DISPLAY 0.680851 (-1385 885);
PAINT WHITE (-1385 885);
WIRE 16 -1 (-625 825)(-1600 825);
FORCEPROP 2 LAST SIG_NAME JTAG_BMC_PLD_TDI
J 0
(-1385 835);
DISPLAY 0.680851 (-1385 835);
PAINT WHITE (-1385 835);
WIRE 16 -1 (-625 725)(-1600 725);
FORCEPROP 2 LAST SIG_NAME TP_PLD_CONN_P5
J 0
(-1385 735);
DISPLAY 0.680851 (-1385 735);
PAINT WHITE (-1385 735);
WIRE 16 -1 (-625 775)(-1600 775);
FORCEPROP 2 LAST SIG_NAME TP_PLD_CONN_P4
J 0
(-1385 785);
DISPLAY 0.680851 (-1385 785);
PAINT WHITE (-1385 785);
WIRE 16 -1 (-625 675)(-1600 675);
FORCEPROP 2 LAST SIG_NAME JTAG_BMC_PLD_TMS
J 0
(-1385 685);
DISPLAY 0.680851 (-1385 685);
PAINT WHITE (-1385 685);
WIRE 16 -1 (-625 575)(-1600 575);
FORCEPROP 2 LAST SIG_NAME JTAG_BMC_PLD_TCK
J 0
(-1385 585);
DISPLAY 0.680851 (-1385 585);
PAINT WHITE (-1385 585);
WIRE 16 -1 (1650 1225)(1650 1075);
WIRE 16 -1 (1650 1400)(1650 1225);
WIRE 16 -1 (1650 1225)(2725 1225);
FORCEPROP 2 LAST SIG_NAME JTAG_PLD_JTAGEN
J 0
(2040 1235);
DISPLAY 0.638298 (2040 1235);
PAINT WHITE (2040 1235);
WIRE 16 -1 (-625 625)(-750 625);
WIRE 16 -1 (-1075 1300)(-1075 1175);
WIRE 16 -1 (-150 4225)(-150 4350);
WIRE 16 -1 (-450 4350)(-450 4225);
WIRE 16 -1 (-150 4350)(-450 4350);
WIRE 16 -1 (-775 4350)(-775 4225);
WIRE 16 -1 (-775 4350)(-450 4350);
WIRE 16 -1 (-3550 3525)(-2225 3525);
FORCEPROP 2 LAST SIG_NAME JTAG_PLD_TDO_R
J 0
(-3435 3535);
DISPLAY 0.680851 (-3435 3535);
PAINT WHITE (-3435 3535);
WIRE 16 -1 (-3550 3200)(-2225 3200);
FORCEPROP 2 LAST SIG_NAME JTAG_PLD_TMS_R
J 0
(-3435 3210);
DISPLAY 0.680851 (-3435 3210);
PAINT WHITE (-3435 3210);
WIRE 16 -1 (-2225 2875)(-3550 2875);
FORCEPROP 2 LAST SIG_NAME JTAG_PLD_TCK_R
J 0
(-3435 2885);
DISPLAY 0.680851 (-3435 2885);
PAINT WHITE (-3435 2885);
WIRE 16 -1 (-150 2725)(-150 2875);
WIRE 16 -1 (275 2875)(-150 2875);
WIRE 16 -1 (-2025 2875)(-150 2875);
FORCEPROP 2 LAST SIG_NAME JTAG_BMC_PLD_TCK
J 0
(-1460 2885);
DISPLAY 0.680851 (-1460 2885);
PAINT WHITE (-1460 2885);
WIRE 16 -1 (-450 4025)(-450 3525);
WIRE 16 -1 (275 3525)(-450 3525);
WIRE 16 -1 (-2025 3525)(-450 3525);
FORCEPROP 2 LAST SIG_NAME JTAG_BMC_PLD_TDO
J 0
(-1460 3535);
DISPLAY 0.680851 (-1460 3535);
PAINT WHITE (-1460 3535);
WIRE 16 -1 (-150 4025)(-150 3200);
WIRE 16 -1 (275 3200)(-150 3200);
WIRE 16 -1 (-2025 3200)(-150 3200);
FORCEPROP 2 LAST SIG_NAME JTAG_BMC_PLD_TMS
J 0
(-1460 3210);
DISPLAY 0.680851 (-1460 3210);
PAINT WHITE (-1460 3210);
WIRE 16 -1 (-775 4025)(-775 3850);
WIRE 16 -1 (275 3850)(-775 3850);
WIRE 16 -1 (-2025 3850)(-775 3850);
FORCEPROP 2 LAST SIG_NAME JTAG_BMC_PLD_TDI
J 0
(-1460 3860);
DISPLAY 0.680851 (-1460 3860);
PAINT WHITE (-1460 3860);
WIRE 16 -1 (-3550 3850)(-2225 3850);
FORCEPROP 2 LAST SIG_NAME JTAG_PLD_TDI_R
J 0
(-3435 3860);
DISPLAY 0.680851 (-3435 3860);
PAINT WHITE (-3435 3860);
DOT 1 (-1200 1175);
DOT 1 (-1200 1575);
DOT 1 (-1075 1575);
DOT 1 (-150 2875);
DOT 1 (1650 1225);
DOT 1 (-450 4350);
DOT 1 (-775 4350);
DOT 1 (-150 3200);
DOT 1 (-775 3850);
DOT 1 (-450 3525);
FORCENOTE
JTAG
(-3825 4250) 0;
DISPLAY LEFT (-3825 4250);
DISPLAY 3.936170 (-3825 4250);
PAINT SKYBLUE (-3825 4250);
FORCENOTE
FOR FPGA PROGRAMMING
(-2350 -150) 0;
DISPLAY LEFT (-2350 -150);
DISPLAY 2.000000 (-2350 -150);
PAINT SKYBLUE (-2350 -150);
FORCENOTE
20210902 MODIFY FOR GT
(-4450 4900) 0;
DISPLAY LEFT (-4450 4900);
DISPLAY 2.510638 (-4450 4900);
PAINT PINK (-4450 4900);
QUIT
